FILE_TYPE = CONNECTIVITY;
{Allegro Design Entry HDL 17.2-2016 S081 (4005846) 1/11/2022}
"PAGE_NUMBER" = 233;
0"NC";
1"P3V3_AUX\g";
2"P3V3_AUX\g";
3"P3V3_AUX\g";
4"P12V_PSU\g";
5"P3V3_AUX\g";
6"GND\g";
7"GND\g";
8"GND\g";
9"GND\g";
10"GND\g";
11"RST_SMB_SWITCH_R_N";
12"PDB_PRSNT_N";
13"FM_AC_PWR_BTN_PDB_N";
14"FM_FAN_PWR_EN_R";
15"FM_GPU_HSC_EN_BUF_R1";
16"HPDB_HSC_PWRGD_R";
17"SMB_FAN_3V3AUX_BUF_R_SCL";
18"SMB_FAN_3V3AUX_BUF_R_SDA";
19"SMB_FAN_3V3AUX_BUF_R_SCL";
20"SMB_FAN_3V3AUX_BUF_R_SDA";
21"HPDB_HSC_PWRGD";
22"FM_GPU_HSC_EN_BUF";
23"FM_FAN_PWR_EN";
24"PDB_PRSNT_N";
25"HPDB_HSC_PWRGD_R";
26"FM_FAN_PWR_EN_R";
27"FM_GPU_HSC_EN_BUF_R1";
28"FM_AC_PWR_BTN_PDB_N"CDS_PHYS_NET_NAME"FM_AC_PWR_BTN_PDB_N";
29"RST_SMB_SWITCH_R_N";
30"RST_SMB_SWITCH_N";
31"FM_AC_PWR_BTN_R_N"CDS_PHYS_NET_NAME"FM_AC_PWR_BTN_R_N";
32"TP_J45_A1"CDS_PHYS_NET_NAME"TP_J45_A1";
33"P3V3_PDB_AUX_ADC";
34"PWRGD_P3V3_AUX_PDB_BUF";
35"SMB_FAN_3V3AUX_BUF_SDA";
36"SMB_FAN_3V3AUX_BUF_SCL";
37"SMB_FAN_3V3AUX_R_SCL";
38"SMB_FAN_3V3AUX_R_SDA";
39"FM_MB_PDB_SMB9_R_EN";
40"SMB_FAN_3V3AUX_SCL";
41"SMB_FAN_3V3AUX_SDA";
42"FM_PDB_BUF_EN_R";
%"Q_RES"
"1","(-4100,-2025)","0","pure_quanta","I10";
;
PART_NUMBER"CS03322FB03"
MATERIAL"CHIP"
TOLERANCE"1%"
PACK_TYPE"0402LF"
VALUE"33.2"
LOCATION"R2796"
CDS_LIB"pure_quanta"
WATTAGE"1/16W"
$SEC"1"
CDS_SEC"1";
"B"
$PN"2"39;
"A"
$PN"1"42;
%"UNIVERSAL_GND"
"1","(-3825,25)","0","logical_power","I11";
;
CDS_LIB"logical_power"
HDL_POWER"GND";
"A"7;
%"CONN60_101062636003K02LF"
"1","(-3200,1150)","0","pure_quanta","I12";
;
PART_NUMBER"DFHD60MR024"
MATERIAL"IO"
PART_TYPE"THLF"
VALUE"CONN60_10106263-6003K02LF"
LOCATION"J45"
CDS_LMAN_SYM_OUTLINE"-250,1000,250,-1000"
NEEDS_NO_SIZE"TRUE"
CDS_LIB"pure_quanta"
$SEC"1"
CDS_SEC"1";
"D3"
$PN"D3"24;
"C3"
$PN"C3"25;
"B3"
$PN"B3"7;
"A3"
$PN"A3"33;
"P6_8"
$PN"P6_8"4;
"P6_7"
$PN"P6_7"4;
"P6_6"
$PN"P6_6"4;
"P6_5"
$PN"P6_5"4;
"P6_4"
$PN"P6_4"4;
"P6_3"
$PN"P6_3"4;
"P6_2"
$PN"P6_2"4;
"P6_1"
$PN"P6_1"4;
"P3_8"
$PN"P3_8"7;
"P3_7"
$PN"P3_7"7;
"P3_6"
$PN"P3_6"7;
"P3_5"
$PN"P3_5"7;
"P3_4"
$PN"P3_4"7;
"P3_3"
$PN"P3_3"7;
"P3_2"
$PN"P3_2"7;
"P3_1"
$PN"P3_1"7;
"P5_8"
$PN"P5_8"4;
"P5_7"
$PN"P5_7"4;
"P5_6"
$PN"P5_6"4;
"P5_5"
$PN"P5_5"4;
"P5_4"
$PN"P5_4"4;
"P5_3"
$PN"P5_3"4;
"P5_2"
$PN"P5_2"4;
"P5_1"
$PN"P5_1"4;
"D1"
$PN"D1"26;
"C1"
$PN"C1"19;
"B1"
$PN"B1"29;
"A1"
$PN"A1"32;
"P4_8"
$PN"P4_8"4;
"P4_7"
$PN"P4_7"4;
"P4_6"
$PN"P4_6"4;
"P4_5"
$PN"P4_5"4;
"P4_4"
$PN"P4_4"4;
"P4_3"
$PN"P4_3"4;
"P4_2"
$PN"P4_2"4;
"P4_1"
$PN"P4_1"4;
"P2_8"
$PN"P2_8"7;
"P2_7"
$PN"P2_7"7;
"P2_6"
$PN"P2_6"7;
"P2_5"
$PN"P2_5"7;
"P2_4"
$PN"P2_4"7;
"P2_3"
$PN"P2_3"7;
"P2_2"
$PN"P2_2"7;
"P2_1"
$PN"P2_1"7;
"P1_8"
$PN"P1_8"7;
"P1_7"
$PN"P1_7"7;
"P1_6"
$PN"P1_6"7;
"P1_5"
$PN"P1_5"7;
"P1_4"
$PN"P1_4"7;
"P1_3"
$PN"P1_3"7;
"P1_2"
$PN"P1_2"7;
"P1_1"
$PN"P1_1"7;
"D2"
$PN"D2"27;
"C2"
$PN"C2"20;
"B2"
$PN"B2"34;
"A2"
$PN"A2"28;
%"UNIVERSAL_GND"
"1","(-2975,-2425)","0","logical_power","I13";
;
HDL_POWER"GND"
CDS_LIB"logical_power";
"A"8;
%"Q_RES"
"1","(-2575,-2650)","0","pure_quanta","I14";
;
PART_NUMBER"CS00002JB13"
PACK_TYPE"0402LF"
VALUE"0"
WATTAGE"1/16W"
MATERIAL"EMPTY"
TOLERANCE"5%"
$LOCATION"R2801"
CDS_LIB"pure_quanta"
CDS_LOCATION"R2801"
$SEC"1"
CDS_SEC"1";
"B"
$PN"2"35;
"A"
$PN"1"38;
%"Q_RES"
"1","(-2575,-2575)","0","pure_quanta","I15";
;
PART_NUMBER"CS00002JB13"
VALUE"0"
MATERIAL"EMPTY"
$LOCATION"R2800"
CDS_LIB"pure_quanta"
PACK_TYPE"0402LF"
TOLERANCE"5%"
WATTAGE"1/16W"
CDS_LOCATION"R2800"
$SEC"1"
CDS_SEC"1";
"B"
$PN"2"36;
"A"
$PN"1"37;
%"LTC4307CMS8"
"1","(-2550,-2175)","0","pure_quanta","I16";
;
PART_NUMBER"AL004307000"
PART_TYPE"SMLF"
VALUE"LTC4307CMS8"
MATERIAL"IC"
$LOCATION"U192"
CDS_LIB"pure_quanta"
NEEDS_NO_SIZE"TRUE"
CDS_LOCATION"U192"
$SEC"1"
CDS_SEC"1";
"READY"
$PN"5"0;
"SDA_OUT"
$PN"7"35;
"SCL_OUT"
$PN"2"36;
"VCC"
$PN"8"2;
"GND"
$PN"4"8;
"SDA_IN"
$PN"6"38;
"SCL_IN"
$PN"3"37;
"ENABLE"
$PN"1"39;
%"UNIVERSAL_GND"
"1","(-1700,-1850)","0","logical_power","I17";
;
CDS_LIB"logical_power"
HDL_POWER"GND";
"A"9;
%"UNIVERSAL_POWER"
"1","(-2050,-1325)","0","logical_power","I18";
;
HDL_POWER"P3V3_AUX"
CDS_LIB"logical_power";
"A"2;
%"Q_CAP"
"1","(-1700,-1600)","2","pure_quanta","I19";
;
PART_NUMBER"CH4104K1B00"
PACK_TYPE"0402"
TOLERANCE"10%"
VOLTAGE"25V"
MATERIAL"X7R"
VALUE"0.1UF"
$LOCATION"C1751"
CDS_LIB"pure_quanta"
CDS_LOCATION"C1751"
$SEC"1"
CDS_SEC"1";
"B"
$PN"2"9;
"A"
$PN"1"2;
%"UNIVERSAL_GND"
"1","(-5725,-2625)","0","logical_power","I2";
;
CDS_LIB"logical_power"
HDL_POWER"GND";
"A"6;
%"Q_RES"
"1","(-525,-2225)","0","pure_quanta","I20";
;
PART_NUMBER"CS03322FB03"
MATERIAL"CHIP"
VALUE"33.2"
TOLERANCE"1%"
$LOCATION"R2812"
CDS_LIB"pure_quanta"
PACK_TYPE"0402LF"
WATTAGE"1/16W"
CDS_LOCATION"R2812"
$SEC"1"
CDS_SEC"1";
"B"
$PN"2"18;
"A"
$PN"1"35;
%"Q_RES"
"1","(-525,-2125)","0","pure_quanta","I21";
;
PART_NUMBER"CS03322FB03"
MATERIAL"CHIP"
TOLERANCE"1%"
VALUE"33.2"
$LOCATION"R2811"
PACK_TYPE"0402LF"
WATTAGE"1/16W"
CDS_LIB"pure_quanta"
CDS_LOCATION"R2811"
$SEC"1"
CDS_SEC"1";
"B"
$PN"2"17;
"A"
$PN"1"36;
%"Q_RES"
"2","(-1250,-1675)","0","pure_quanta","I22";
;
PART_NUMBER"CS24702JB10"
WATTAGE"1/16W"
TOLERANCE"5%"
VALUE"4.7K"
MATERIAL"EMPTY"
PACK_TYPE"0402LF"
$LOCATION"R2805"
CDS_LIB"pure_quanta"
CDS_LOCATION"R2805"
$SEC"1"
CDS_SEC"1";
"A"
$PN"1"3;
"B"
$PN"2"36;
%"UNIVERSAL_POWER"
"1","(-1250,-1375)","0","logical_power","I23";
;
HDL_POWER"P3V3_AUX"
CDS_LIB"logical_power";
"A"3;
%"Q_RES"
"2","(-1000,-1700)","0","pure_quanta","I24";
;
PART_NUMBER"CS24702JB10"
PACK_TYPE"0402LF"
WATTAGE"1/16W"
TOLERANCE"5%"
MATERIAL"EMPTY"
VALUE"4.7K"
$LOCATION"R2807"
CDS_LIB"pure_quanta"
CDS_LOCATION"R2807"
$SEC"1"
CDS_SEC"1";
"A"
$PN"1"3;
"B"
$PN"2"35;
%"Q_RES"
"2","(-5725,-2250)","0","pure_quanta","I3";
;
PART_NUMBER"CS41002FB09"
WATTAGE"1/16W"
MATERIAL"CHIP"
VALUE"100K"
TOLERANCE"1%"
PACK_TYPE"0402LF"
$LOCATION"R4769"
CDS_LIB"pure_quanta"
CDS_LOCATION"R4769"
$SEC"1"
CDS_SEC"1";
"A"
$PN"1"42;
"B"
$PN"2"6;
%"Q_RES"
"1","(-5200,1900)","0","pure_quanta","I34";
;
PART_NUMBER"CS00002JB13"
MATERIAL"CHIP"
TOLERANCE"5%"
VALUE"0"
$LOCATION"R2905"
WATTAGE"1/16W"
PACK_TYPE"0402LF"
CDS_LIB"pure_quanta"
CDS_LOCATION"R2905"
$SEC"1"
CDS_SEC"1";
"B"
$PN"2"29;
"A"
$PN"1"30;
%"Q_RES"
"1","(-5200,2000)","0","pure_quanta","I35";
;
PART_NUMBER"CS00002JB13"
TOLERANCE"5%"
VALUE"0"
MATERIAL"CHIP"
$LOCATION"R4721"
PACK_TYPE"0402LF"
WATTAGE"1/16W"
CDS_LIB"pure_quanta"
CDS_LOCATION"R4721"
$SEC"1"
CDS_SEC"1";
"B"
$PN"2"28;
"A"
$PN"1"31;
%"UNIVERSAL_POWER"
"1","(-2325,1700)","0","logical_power","I36";
;
HDL_POWER"P12V_PSU"
CDS_LIB"logical_power";
"A"4;
%"Q_RES"
"1","(-1600,1850)","0","pure_quanta","I37";
;
PART_NUMBER"CS00002JB13"
VALUE"0"
TOLERANCE"5%"
MATERIAL"CHIP"
$LOCATION"R2906"
CDS_LIB"pure_quanta"
WATTAGE"1/16W"
PACK_TYPE"0402LF"
CDS_LOCATION"R2906"
$SEC"1"
CDS_SEC"1";
"B"
$PN"2"22;
"A"
$PN"1"27;
%"Q_RES"
"1","(-1600,1900)","0","pure_quanta","I38";
;
PART_NUMBER"CS00002JB13"
MATERIAL"CHIP"
TOLERANCE"5%"
VALUE"0"
$LOCATION"R2803"
PACK_TYPE"0402LF"
WATTAGE"1/16W"
CDS_LIB"pure_quanta"
$LOCATION"R2803"
CDS_LOCATION"R2803"
$SEC"1"
CDS_SEC"1";
"B"
$PN"2"23;
"A"
$PN"1"26;
%"Q_RES"
"1","(-1600,1950)","0","pure_quanta","I39";
;
PART_NUMBER"CS00002JB13"
MATERIAL"CHIP"
VALUE"0"
TOLERANCE"5%"
$LOCATION"R2802"
WATTAGE"1/16W"
PACK_TYPE"0402LF"
CDS_LIB"pure_quanta"
$LOCATION"R2802"
CDS_LOCATION"R2802"
$SEC"1"
CDS_SEC"1";
"B"
$PN"2"21;
"A"
$PN"1"25;
%"Q_RES"
"2","(-5800,-1700)","0","pure_quanta","I4";
;
PART_NUMBER"CS24702JB10"
VALUE"4.7K"
TOLERANCE"5%"
MATERIAL"EMPTY"
WATTAGE"1/16W"
PACK_TYPE"0402LF"
$LOCATION"R2950"
CDS_LIB"pure_quanta"
CDS_LOCATION"R2950"
$SEC"1"
CDS_SEC"1";
"A"
$PN"1"1;
"B"
$PN"2"42;
%"Q_RES"
"2","(-1175,2350)","0","pure_quanta","I41";
;
PART_NUMBER"CS24702JB10"
PACK_TYPE"0402LF"
VALUE"4.7K"
TOLERANCE"5%"
MATERIAL"CHIP"
WATTAGE"1/16W"
$LOCATION"R4701"
CDS_LIB"pure_quanta"
CDS_LOCATION"R4701"
$SEC"1"
CDS_SEC"1";
"A"
$PN"1"5;
"B"
$PN"2"23;
%"UNIVERSAL_POWER"
"1","(-1175,2650)","0","logical_power","I42";
;
HDL_POWER"P3V3_AUX"
CDS_LIB"logical_power";
"A"5;
%"UNIVERSAL_POWER"
"1","(-5800,-1425)","0","logical_power","I5";
;
HDL_POWER"P3V3_AUX"
CDS_LIB"logical_power";
"A"1;
%"Q_CAP"
"2","(750,550)","0","pure_quanta","I51";
;
PART_NUMBER"CH4104K1B00"
VALUE"0.1UF"
MATERIAL"EMPTY"
$LOCATION"C2371"
CDS_LIB"pure_quanta"
PACK_TYPE"0402"
TOLERANCE"10%"
VOLTAGE"25V"
CDS_LOCATION"C2371"
$SEC"1"
CDS_SEC"1";
"A"
$PN"1"13;
"B"
$PN"2"10;
%"Q_CAP"
"2","(750,725)","0","pure_quanta","I52";
;
PART_NUMBER"CH4104K1B00"
VALUE"0.1UF"
MATERIAL"EMPTY"
$LOCATION"C2297"
VOLTAGE"25V"
TOLERANCE"10%"
PACK_TYPE"0402"
CDS_LIB"pure_quanta"
CDS_LOCATION"C2297"
$SEC"1"
CDS_SEC"1";
"A"
$PN"1"15;
"B"
$PN"2"10;
%"Q_CAP"
"2","(750,875)","0","pure_quanta","I53";
;
PART_NUMBER"CH4104K1B00"
VALUE"0.1UF"
MATERIAL"EMPTY"
$LOCATION"C2296"
VOLTAGE"25V"
TOLERANCE"10%"
PACK_TYPE"0402"
CDS_LIB"pure_quanta"
CDS_LOCATION"C2296"
$SEC"1"
CDS_SEC"1";
"A"
$PN"1"14;
"B"
$PN"2"10;
%"Q_CAP"
"2","(750,1025)","0","pure_quanta","I54";
;
PART_NUMBER"CH4104K1B00"
VALUE"0.1UF"
MATERIAL"EMPTY"
$LOCATION"C2295"
VOLTAGE"25V"
TOLERANCE"10%"
PACK_TYPE"0402"
CDS_LIB"pure_quanta"
CDS_LOCATION"C2295"
$SEC"1"
CDS_SEC"1";
"A"
$PN"1"16;
"B"
$PN"2"10;
%"Q_CAP"
"2","(750,1175)","0","pure_quanta","I55";
;
PART_NUMBER"CH4104K1B00"
MATERIAL"EMPTY"
VALUE"0.1UF"
$LOCATION"C2294"
VOLTAGE"25V"
TOLERANCE"10%"
PACK_TYPE"0402"
CDS_LIB"pure_quanta"
CDS_LOCATION"C2294"
$SEC"1"
CDS_SEC"1";
"A"
$PN"1"12;
"B"
$PN"2"10;
%"UNIVERSAL_GND"
"1","(1200,350)","0","logical_power","I56";
;
CDS_LIB"logical_power"
HDL_POWER"GND";
"A"10;
%"Q_CAP"
"2","(750,1325)","0","pure_quanta","I57";
;
PART_NUMBER"CH4104K1B00"
VALUE"0.1UF"
MATERIAL"EMPTY"
$LOCATION"C2293"
VOLTAGE"25V"
TOLERANCE"10%"
PACK_TYPE"0402"
CDS_LIB"pure_quanta"
CDS_LOCATION"C2293"
$SEC"1"
CDS_SEC"1";
"A"
$PN"1"11;
"B"
$PN"2"10;
%"Q_RES"
"1","(-4100,-2225)","0","pure_quanta","I8";
;
PART_NUMBER"CS03322FB03"
TOLERANCE"1%"
MATERIAL"CHIP"
VALUE"33.2"
LOCATION"R3114"
WATTAGE"1/16W"
PACK_TYPE"0402LF"
CDS_LIB"pure_quanta"
$SEC"1"
CDS_SEC"1";
"B"
$PN"2"38;
"A"
$PN"1"41;
%"Q_RES"
"1","(-4100,-2125)","0","pure_quanta","I9";
;
PART_NUMBER"CS03322FB03"
TOLERANCE"1%"
VALUE"33.2"
MATERIAL"CHIP"
LOCATION"R3113"
WATTAGE"1/16W"
PACK_TYPE"0402LF"
CDS_LIB"pure_quanta"
$SEC"1"
CDS_SEC"1";
"B"
$PN"2"37;
"A"
$PN"1"40;
END.
